# BASEBOARD_FAB2 (Tioga Pass) — schematic netlist excerpt (pin names and nets, part order shuffled) for the footprints in the layout excerpt that follows; sources: Cadence DE-HDL packaged netlist, KiCad conversion of Wiwynn_Tioga_Pass_MB.brd

C4W1  CAP  220PF 50V 10% X7R  pkg 0402LF  page 211 : A = A_TSENSE_PVCCIO_CPU0 ; B = GND
R2U24  RES  0.0 5% CHIP  pkg 0402  page 107 : A = P3E_CPU0_PE1_SS_RXP<5> ; B = P3E_CPU0_PE1_SS_R_RXP<5>
C2T10  CAP  0.22UF 16V 10% X7R  pkg 0402  page 185 : A = P3E_PCH_M2_TX_C_DP<1> ; B = P3E_PCH_M2_TX_DP<1>

(kicad_pcb
	(version 20260206)
	(generator "pcbnew")
	(generator_version "10.0")
	(general
		(thickness 1.6)
		(legacy_teardrops no)
	)
	(paper "A4")
	(title_block
		(title "Wiwynn_Tioga_Pass_MB.brd")
		(comment 1 "Tioga Pass / footprints 3279-3281 of 4770")
	)
	(layers
		(0 "F.Cu" signal "TOP")
		(4 "In1.Cu" signal "L2GND")
		(6 "In2.Cu" signal "L3")
		(8 "In3.Cu" signal "L4GND")
		(10 "In4.Cu" signal "L5")
		(12 "In5.Cu" signal "L6GND")
		(14 "In6.Cu" signal "L7VCC")
		(16 "In7.Cu" signal "L8VCC")
		(18 "In8.Cu" signal "L9GND")
		(20 "In9.Cu" signal "L10")
		(22 "In10.Cu" signal "L11GND")
		(24 "In11.Cu" signal "L12")
		(26 "In12.Cu" signal "L13GND")
		(2 "B.Cu" signal "BOTTOM")
		(9 "F.Adhes" user "F.Adhesive")
		(11 "B.Adhes" user "B.Adhesive")
		(13 "F.Paste" user "Package Geometry/Pastemask Top")
		(15 "B.Paste" user "Package Geometry/Pastemask Bottom")
		(5 "F.SilkS" user "Ref Des/Silkscreen Top")
		(7 "B.SilkS" user "Ref Des/Silkscreen Bottom")
		(1 "F.Mask" user "Board Geometry/Soldermask Top")
		(3 "B.Mask" user "Board Geometry/Soldermask Bottom")
		(17 "Dwgs.User" user "User.Drawings")
		(19 "Cmts.User" user "User.Comments")
		(21 "Eco1.User" user "User.Eco1")
		(23 "Eco2.User" user "User.Eco2")
		(25 "Edge.Cuts" user "Board Geometry/Outline")
		(27 "Margin" user)
		(31 "F.CrtYd" user "Package Geometry/Place Bound Top")
		(29 "B.CrtYd" user "Package Geometry/Place Bound Bottom")
		(35 "F.Fab" user "Ref Des/Assembly Top")
		(33 "B.Fab" user "Ref Des/Assembly Bottom")
	)
	(footprint ""
		(layer "B.Cu")
		(at 351.13468 -89.067132 90)
		(property "Reference" "C4W1"
			(at 0.8382 -0.67818 90)
			(unlocked yes)
			(layer "B.SilkS")
			(effects
				(font
					(size 0.4064 0.254)
					(thickness 0.1524)
				)
				(justify left mirror)
			)
		)
		(property "Value" ""
			(at 0 0 90)
			(layer "B.Fab")
			(effects
				(font
					(size 1.27 1.27)
				)
				(justify mirror)
			)
		)
		(duplicate_pad_numbers_are_jumpers no)
		(fp_poly
			(pts
				(xy -0.3048 -0.1016) (xy -0.3048 0.9906) (xy 0.3048 0.9906) (xy 0.3048 -0.1016)
			)
			(stroke
				(width 0)
				(type default)
			)
			(fill no)
			(layer "B.CrtYd")
		)
		(fp_line
			(start 0.3048 -0.1016)
			(end 0.3048 0.9906)
			(stroke
				(width 0.1)
				(type default)
			)
			(layer "B.Fab")
		)
		(fp_line
			(start -0.3048 -0.1016)
			(end 0.3048 -0.1016)
			(stroke
				(width 0.1)
				(type default)
			)
			(layer "B.Fab")
		)
		(fp_line
			(start 0.3048 0.9906)
			(end -0.3048 0.9906)
			(stroke
				(width 0.1)
				(type default)
			)
			(layer "B.Fab")
		)
		(fp_line
			(start -0.3048 0.9906)
			(end -0.3048 -0.1016)
			(stroke
				(width 0.1)
				(type default)
			)
			(layer "B.Fab")
		)
		(pad "1" smd rect
			(at 0 0 270)
			(size 0.508 0.508)
			(layers "B.Cu" "B.Mask" "B.Paste")
			(net "A_TSENSE_PVCCIO_CPU0")
		)
		(pad "2" smd rect
			(at 0 0.889 270)
			(size 0.508 0.508)
			(layers "B.Cu" "B.Mask" "B.Paste")
			(net "GND")
		)
		(zone
			(layer "B.Cu")
			(hatch none 0.5)
			(connect_pads
				(clearance 0)
			)
			(min_thickness 0.25)
			(keepout
				(tracks allowed)
				(vias not_allowed)
				(pads allowed)
				(copperpour not_allowed)
				(footprints allowed)
			)
			(placement
				(enabled no)
				(sheetname "")
			)
			(fill
				(thermal_gap 0.5)
				(thermal_bridge_width 0.5)
				(island_removal_mode 0)
			)
			(polygon
				(pts
					(xy 351.38868 -89.321132) (xy 351.38868 -88.813132) (xy 351.76968 -88.813132) (xy 351.76968 -89.321132)
				)
			)
		)
		(zone
			(layer "B.Cu")
			(hatch none 0.5)
			(connect_pads
				(clearance 0)
			)
			(min_thickness 0.25)
			(keepout
				(tracks not_allowed)
				(vias allowed)
				(pads allowed)
				(copperpour not_allowed)
				(footprints allowed)
			)
			(placement
				(enabled no)
				(sheetname "")
			)
			(fill
				(thermal_gap 0.5)
				(thermal_bridge_width 0.5)
				(island_removal_mode 0)
			)
			(polygon
				(pts
					(xy 351.76968 -89.321132) (xy 351.76968 -88.813132) (xy 351.38868 -88.813132) (xy 351.38868 -89.321132)
				)
			)
		)
	)
	(footprint ""
		(layer "B.Cu")
		(at 385.34594 -30.571694 90)
		(property "Reference" "C2T10"
			(at 0 0 90)
			(layer "B.SilkS")
			(hide yes)
			(effects
				(font
					(size 1.27 1.27)
				)
				(justify mirror)
			)
		)
		(property "Value" ""
			(at 0 0 90)
			(layer "B.Fab")
			(effects
				(font
					(size 1.27 1.27)
				)
				(justify mirror)
			)
		)
		(duplicate_pad_numbers_are_jumpers no)
		(fp_poly
			(pts
				(xy -0.3048 -0.1016) (xy -0.3048 0.9906) (xy 0.3048 0.9906) (xy 0.3048 -0.1016)
			)
			(stroke
				(width 0)
				(type default)
			)
			(fill no)
			(layer "B.CrtYd")
		)
		(fp_line
			(start 0.3048 -0.1016)
			(end 0.3048 0.9906)
			(stroke
				(width 0.1)
				(type default)
			)
			(layer "B.Fab")
		)
		(fp_line
			(start -0.3048 -0.1016)
			(end 0.3048 -0.1016)
			(stroke
				(width 0.1)
				(type default)
			)
			(layer "B.Fab")
		)
		(fp_line
			(start 0.3048 0.9906)
			(end -0.3048 0.9906)
			(stroke
				(width 0.1)
				(type default)
			)
			(layer "B.Fab")
		)
		(fp_line
			(start -0.3048 0.9906)
			(end -0.3048 -0.1016)
			(stroke
				(width 0.1)
				(type default)
			)
			(layer "B.Fab")
		)
		(pad "1" smd rect
			(at 0 0 270)
			(size 0.508 0.508)
			(layers "B.Cu" "B.Mask" "B.Paste")
			(net "P3E_PCH_M2_TX_C_DP<1>")
		)
		(pad "2" smd rect
			(at 0 0.889 270)
			(size 0.508 0.508)
			(layers "B.Cu" "B.Mask" "B.Paste")
			(net "P3E_PCH_M2_TX_DP<1>")
		)
		(zone
			(layer "B.Cu")
			(hatch none 0.5)
			(connect_pads
				(clearance 0)
			)
			(min_thickness 0.25)
			(keepout
				(tracks allowed)
				(vias not_allowed)
				(pads allowed)
				(copperpour not_allowed)
				(footprints allowed)
			)
			(placement
				(enabled no)
				(sheetname "")
			)
			(fill
				(thermal_gap 0.5)
				(thermal_bridge_width 0.5)
				(island_removal_mode 0)
			)
			(polygon
				(pts
					(xy 385.59994 -30.825694) (xy 385.59994 -30.317694) (xy 385.98094 -30.317694) (xy 385.98094 -30.825694)
				)
			)
		)
		(zone
			(layer "B.Cu")
			(hatch none 0.5)
			(connect_pads
				(clearance 0)
			)
			(min_thickness 0.25)
			(keepout
				(tracks not_allowed)
				(vias allowed)
				(pads allowed)
				(copperpour not_allowed)
				(footprints allowed)
			)
			(placement
				(enabled no)
				(sheetname "")
			)
			(fill
				(thermal_gap 0.5)
				(thermal_bridge_width 0.5)
				(island_removal_mode 0)
			)
			(polygon
				(pts
					(xy 385.98094 -30.825694) (xy 385.98094 -30.317694) (xy 385.59994 -30.317694) (xy 385.59994 -30.825694)
				)
			)
		)
	)
	(footprint ""
		(layer "B.Cu")
		(at 347.316806 -60.368434)
		(property "Reference" "R2U24"
			(at 0 0 0)
			(layer "B.SilkS")
			(hide yes)
			(effects
				(font
					(size 1.27 1.27)
				)
				(justify mirror)
			)
		)
		(property "Value" ""
			(at 0 0 0)
			(layer "B.Fab")
			(effects
				(font
					(size 1.27 1.27)
				)
				(justify mirror)
			)
		)
		(duplicate_pad_numbers_are_jumpers no)
		(fp_poly
			(pts
				(xy 0.2794 -0.1016) (xy -0.2794 -0.1016) (xy -0.2794 0.9906) (xy 0.2794 0.9906)
			)
			(stroke
				(width 0)
				(type default)
			)
			(fill no)
			(layer "B.CrtYd")
		)
		(fp_line
			(start -0.2794 -0.1016)
			(end 0.2794 -0.1016)
			(stroke
				(width 0.1)
				(type default)
			)
			(layer "B.Fab")
		)
		(fp_line
			(start -0.2794 0.9906)
			(end -0.2794 -0.1016)
			(stroke
				(width 0.1)
				(type default)
			)
			(layer "B.Fab")
		)
		(fp_line
			(start 0.2794 -0.1016)
			(end 0.2794 0.9906)
			(stroke
				(width 0.1)
				(type default)
			)
			(layer "B.Fab")
		)
		(fp_line
			(start 0.2794 0.9906)
			(end -0.2794 0.9906)
			(stroke
				(width 0.1)
				(type default)
			)
			(layer "B.Fab")
		)
		(pad "1" smd rect
			(at 0 0 180)
			(size 0.508 0.508)
			(layers "B.Cu" "B.Mask" "B.Paste")
			(net "P3E_CPU0_PE1_SS_RXP<5>")
		)
		(pad "2" smd rect
			(at 0 0.889 180)
			(size 0.508 0.508)
			(layers "B.Cu" "B.Mask" "B.Paste")
			(net "P3E_CPU0_PE1_SS_R_RXP<5>")
		)
		(zone
			(layer "B.Cu")
			(hatch none 0.5)
			(connect_pads
				(clearance 0)
			)
			(min_thickness 0.25)
			(keepout
				(tracks allowed)
				(vias not_allowed)
				(pads allowed)
				(copperpour not_allowed)
				(footprints allowed)
			)
			(placement
				(enabled no)
				(sheetname "")
			)
			(fill
				(thermal_gap 0.5)
				(thermal_bridge_width 0.5)
				(island_removal_mode 0)
			)
			(polygon
				(pts
					(xy 347.570806 -60.114434) (xy 347.062806 -60.114434) (xy 347.062806 -59.733434) (xy 347.570806 -59.733434)
				)
			)
		)
	)
)
